# T6G (Grand Teton) — schematic netlist excerpt (pin names and nets, part order shuffled) for the footprints in the layout excerpt that follows; sources: Cadence DE-HDL packaged netlist, KiCad conversion of 04192023_DAF0TMB3IC0_F0TG_MB_C_brd_V02_OCP.brd

C6724  Q_CAP_DIFFBUS  DIFF BUS_0.22UF 6.3V 20% X6S  pkg C0201  page 341 : \1\ = P5E_CPU1_P2_TX_BUF_C_DN<15> ; \2\ = P5E_CPU1_P2_TX_BUF_DN<15>

(kicad_pcb
	(version 20260206)
	(generator "pcbnew")
	(generator_version "10.0")
	(general
		(thickness 1.6)
		(legacy_teardrops no)
	)
	(paper "A4")
	(title_block
		(title "04192023_DAF0TMB3IC0_F0TG_MB_C_brd_V02_OCP.brd")
		(comment 1 "Grand Teton / footprints 4889-4889 of 8354")
	)
	(layers
		(0 "F.Cu" signal "TOP")
		(4 "In1.Cu" signal "GND")
		(6 "In2.Cu" signal "IN1")
		(8 "In3.Cu" signal "GND1")
		(10 "In4.Cu" signal "IN2")
		(12 "In5.Cu" signal "GND2")
		(14 "In6.Cu" signal "IN3")
		(16 "In7.Cu" signal "GND3")
		(18 "In8.Cu" signal "VCC")
		(20 "In9.Cu" signal "VCC1")
		(22 "In10.Cu" signal "GND4")
		(24 "In11.Cu" signal "IN4")
		(26 "In12.Cu" signal "GND5")
		(28 "In13.Cu" signal "IN5")
		(30 "In14.Cu" signal "GND6")
		(32 "In15.Cu" signal "IN6")
		(34 "In16.Cu" signal "GND7")
		(2 "B.Cu" signal "BOTTOM")
		(9 "F.Adhes" user "F.Adhesive")
		(11 "B.Adhes" user "B.Adhesive")
		(13 "F.Paste" user "Package Geometry/Pastemask Top")
		(15 "B.Paste" user "Package Geometry/Pastemask Bottom")
		(5 "F.SilkS" user "Ref Des/Silkscreen Top")
		(7 "B.SilkS" user "Ref Des/Silkscreen Bottom")
		(1 "F.Mask" user "Board Geometry/Soldermask Top")
		(3 "B.Mask" user "Board Geometry/Soldermask Bottom")
		(17 "Dwgs.User" user "User.Drawings")
		(19 "Cmts.User" user "User.Comments")
		(21 "Eco1.User" user "User.Eco1")
		(23 "Eco2.User" user "User.Eco2")
		(25 "Edge.Cuts" user "Board Geometry/Outline")
		(27 "Margin" user)
		(31 "F.CrtYd" user "Package Geometry/Place Bound Top")
		(29 "B.CrtYd" user "Package Geometry/Place Bound Bottom")
		(35 "F.Fab" user "Ref Des/Assembly Top")
		(33 "B.Fab" user "Ref Des/Assembly Bottom")
	)
	(footprint ""
		(layer "F.Cu")
		(at 160.817306 -408.517344 -90)
		(property "Reference" "C6724"
			(at 0 0 270)
			(layer "F.SilkS")
			(hide yes)
			(effects
				(font
					(size 1.27 1.27)
				)
			)
		)
		(property "Value" ""
			(at 0 0 270)
			(layer "F.Fab")
			(effects
				(font
					(size 1.27 1.27)
				)
			)
		)
		(duplicate_pad_numbers_are_jumpers no)
		(fp_line
			(start -0.299974 0.150114)
			(end -0.299974 -0.150114)
			(stroke
				(width 0.1)
				(type default)
			)
			(layer "F.Fab")
		)
		(fp_line
			(start 0.299974 0.150114)
			(end -0.299974 0.150114)
			(stroke
				(width 0.1)
				(type default)
			)
			(layer "F.Fab")
		)
		(fp_line
			(start -0.299974 -0.150114)
			(end 0.299974 -0.150114)
			(stroke
				(width 0.1)
				(type default)
			)
			(layer "F.Fab")
		)
		(fp_line
			(start 0.299974 -0.150114)
			(end 0.299974 0.150114)
			(stroke
				(width 0.1)
				(type default)
			)
			(layer "F.Fab")
		)
		(pad "1" smd rect
			(at -0.2667 0 270)
			(size 0.3048 0.381)
			(layers "F.Cu" "F.Mask" "F.Paste")
			(net "P5E_CPU1_P2_TX_BUF_C_DN<15>")
		)
		(pad "2" smd rect
			(at 0.2667 0 270)
			(size 0.3048 0.381)
			(layers "F.Cu" "F.Mask" "F.Paste")
			(net "P5E_CPU1_P2_TX_BUF_DN<15>")
		)
	)
)
